(kicad_pcb
	(version 20260206)
	(generator "pcbnew")
	(generator_version "10.0")
	(general
		(thickness 1.6)
		(legacy_teardrops no)
	)
	(paper "A4")
	(title_block
		(title "03242023_DA0F0TMBIJ0_F0T_Motherboard_J_brd_V01_OCP.brd")
		(comment 1 "Grand Teton / footprints 1541-1546 of 6105")
	)
	(layers
		(0 "F.Cu" signal "TOP")
		(4 "In1.Cu" signal "GND")
		(6 "In2.Cu" signal "IN1")
		(8 "In3.Cu" signal "GND1")
		(10 "In4.Cu" signal "IN2")
		(12 "In5.Cu" signal "GND2")
		(14 "In6.Cu" signal "IN3")
		(16 "In7.Cu" signal "GND3")
		(18 "In8.Cu" signal "VCC")
		(20 "In9.Cu" signal "VCC1")
		(22 "In10.Cu" signal "GND4")
		(24 "In11.Cu" signal "IN4")
		(26 "In12.Cu" signal "GND5")
		(28 "In13.Cu" signal "IN5")
		(30 "In14.Cu" signal "GND6")
		(32 "In15.Cu" signal "IN6")
		(34 "In16.Cu" signal "GND7")
		(2 "B.Cu" signal "BOTTOM")
		(9 "F.Adhes" user "F.Adhesive")
		(11 "B.Adhes" user "B.Adhesive")
		(13 "F.Paste" user "Package Geometry/Pastemask Top")
		(15 "B.Paste" user "Package Geometry/Pastemask Bottom")
		(5 "F.SilkS" user "Ref Des/Silkscreen Top")
		(7 "B.SilkS" user "Ref Des/Silkscreen Bottom")
		(1 "F.Mask" user "Board Geometry/Soldermask Top")
		(3 "B.Mask" user "Board Geometry/Soldermask Bottom")
		(17 "Dwgs.User" user "User.Drawings")
		(19 "Cmts.User" user "User.Comments")
		(21 "Eco1.User" user "User.Eco1")
		(23 "Eco2.User" user "User.Eco2")
		(25 "Edge.Cuts" user "Board Geometry/Outline")
		(27 "Margin" user)
		(31 "F.CrtYd" user "Package Geometry/Place Bound Top")
		(29 "B.CrtYd" user "Package Geometry/Place Bound Bottom")
		(35 "F.Fab" user "Ref Des/Assembly Top")
		(33 "B.Fab" user "Ref Des/Assembly Bottom")
	)
	(footprint ""
		(layer "F.Cu")
		(at 439.262266 -124.680726 180)
		(property "Reference" "R1735"
			(at 0 0 180)
			(layer "F.SilkS")
			(hide yes)
			(effects
				(font
					(size 1.27 1.27)
				)
			)
		)
		(property "Value" ""
			(at 0 0 180)
			(layer "F.Fab")
			(effects
				(font
					(size 1.27 1.27)
				)
			)
		)
		(duplicate_pad_numbers_are_jumpers no)
		(fp_line
			(start 0.7874 0.4064)
			(end -0.7874 0.4064)
			(stroke
				(width 0.1524)
				(type default)
			)
			(layer "F.SilkS")
		)
		(fp_line
			(start 0.7874 -0.4064)
			(end 0.7874 0.4064)
			(stroke
				(width 0.1524)
				(type default)
			)
			(layer "F.SilkS")
		)
		(fp_line
			(start -0.7874 0.4064)
			(end -0.7874 -0.4064)
			(stroke
				(width 0.1524)
				(type default)
			)
			(layer "F.SilkS")
		)
		(fp_line
			(start -0.7874 -0.4064)
			(end 0.7874 -0.4064)
			(stroke
				(width 0.1524)
				(type default)
			)
			(layer "F.SilkS")
		)
		(fp_line
			(start 0.67945 0.3048)
			(end 0.120396 0.3048)
			(stroke
				(width 0.1)
				(type default)
			)
			(layer "F.Fab")
		)
		(fp_line
			(start 0.67945 -0.3048)
			(end 0.67945 0.3048)
			(stroke
				(width 0.1)
				(type default)
			)
			(layer "F.Fab")
		)
		(fp_line
			(start 0.12065 -0.2794)
			(end 0.12065 -0.3048)
			(stroke
				(width 0.1)
				(type default)
			)
			(layer "F.Fab")
		)
		(fp_line
			(start 0.12065 -0.3048)
			(end 0.67945 -0.3048)
			(stroke
				(width 0.1)
				(type default)
			)
			(layer "F.Fab")
		)
		(fp_line
			(start 0.120396 0.3048)
			(end 0.120396 0.2794)
			(stroke
				(width 0.1)
				(type default)
			)
			(layer "F.Fab")
		)
		(fp_line
			(start 0.120396 0.2794)
			(end -0.12065 0.2794)
			(stroke
				(width 0.1)
				(type default)
			)
			(layer "F.Fab")
		)
		(fp_line
			(start -0.12065 0.3048)
			(end -0.67945 0.3048)
			(stroke
				(width 0.1)
				(type default)
			)
			(layer "F.Fab")
		)
		(fp_line
			(start -0.12065 0.2794)
			(end -0.12065 0.3048)
			(stroke
				(width 0.1)
				(type default)
			)
			(layer "F.Fab")
		)
		(fp_line
			(start -0.12065 -0.2794)
			(end 0.12065 -0.2794)
			(stroke
				(width 0.1)
				(type default)
			)
			(layer "F.Fab")
		)
		(fp_line
			(start -0.12065 -0.305054)
			(end -0.12065 -0.2794)
			(stroke
				(width 0.1)
				(type default)
			)
			(layer "F.Fab")
		)
		(fp_line
			(start -0.67945 0.3048)
			(end -0.67945 -0.305054)
			(stroke
				(width 0.1)
				(type default)
			)
			(layer "F.Fab")
		)
		(fp_line
			(start -0.67945 -0.305054)
			(end -0.12065 -0.305054)
			(stroke
				(width 0.1)
				(type default)
			)
			(layer "F.Fab")
		)
		(pad "1" smd circle
			(at -0.40005 0 180)
			(size 0 0)
			(layers "F.Cu" "F.Mask" "F.Paste")
			(net "PVNN_TERM_CPU0")
		)
		(pad "2" smd circle
			(at 0.40005 0 180)
			(size 0 0)
			(layers "F.Cu" "F.Mask" "F.Paste")
			(net "SVID_DIO1_CPU0_R")
		)
	)
	(footprint ""
		(layer "F.Cu")
		(at 468.49157 -44.887388)
		(property "Reference" "R1594"
			(at 0 0 0)
			(layer "F.SilkS")
			(hide yes)
			(effects
				(font
					(size 1.27 1.27)
				)
			)
		)
		(property "Value" ""
			(at 0 0 0)
			(layer "F.Fab")
			(effects
				(font
					(size 1.27 1.27)
				)
			)
		)
		(duplicate_pad_numbers_are_jumpers no)
		(fp_line
			(start -0.7874 -0.4064)
			(end 0.7874 -0.4064)
			(stroke
				(width 0.1524)
				(type default)
			)
			(layer "F.SilkS")
		)
		(fp_line
			(start -0.7874 0.4064)
			(end -0.7874 -0.4064)
			(stroke
				(width 0.1524)
				(type default)
			)
			(layer "F.SilkS")
		)
		(fp_line
			(start 0.7874 -0.4064)
			(end 0.7874 0.4064)
			(stroke
				(width 0.1524)
				(type default)
			)
			(layer "F.SilkS")
		)
		(fp_line
			(start 0.7874 0.4064)
			(end -0.7874 0.4064)
			(stroke
				(width 0.1524)
				(type default)
			)
			(layer "F.SilkS")
		)
		(fp_line
			(start -0.67945 -0.305054)
			(end -0.12065 -0.305054)
			(stroke
				(width 0.1)
				(type default)
			)
			(layer "F.Fab")
		)
		(fp_line
			(start -0.67945 0.3048)
			(end -0.67945 -0.305054)
			(stroke
				(width 0.1)
				(type default)
			)
			(layer "F.Fab")
		)
		(fp_line
			(start -0.12065 -0.305054)
			(end -0.12065 -0.2794)
			(stroke
				(width 0.1)
				(type default)
			)
			(layer "F.Fab")
		)
		(fp_line
			(start -0.12065 -0.2794)
			(end 0.12065 -0.2794)
			(stroke
				(width 0.1)
				(type default)
			)
			(layer "F.Fab")
		)
		(fp_line
			(start -0.12065 0.2794)
			(end -0.12065 0.3048)
			(stroke
				(width 0.1)
				(type default)
			)
			(layer "F.Fab")
		)
		(fp_line
			(start -0.12065 0.3048)
			(end -0.67945 0.3048)
			(stroke
				(width 0.1)
				(type default)
			)
			(layer "F.Fab")
		)
		(fp_line
			(start 0.120396 0.2794)
			(end -0.12065 0.2794)
			(stroke
				(width 0.1)
				(type default)
			)
			(layer "F.Fab")
		)
		(fp_line
			(start 0.120396 0.3048)
			(end 0.120396 0.2794)
			(stroke
				(width 0.1)
				(type default)
			)
			(layer "F.Fab")
		)
		(fp_line
			(start 0.12065 -0.3048)
			(end 0.67945 -0.3048)
			(stroke
				(width 0.1)
				(type default)
			)
			(layer "F.Fab")
		)
		(fp_line
			(start 0.12065 -0.2794)
			(end 0.12065 -0.3048)
			(stroke
				(width 0.1)
				(type default)
			)
			(layer "F.Fab")
		)
		(fp_line
			(start 0.67945 -0.3048)
			(end 0.67945 0.3048)
			(stroke
				(width 0.1)
				(type default)
			)
			(layer "F.Fab")
		)
		(fp_line
			(start 0.67945 0.3048)
			(end 0.120396 0.3048)
			(stroke
				(width 0.1)
				(type default)
			)
			(layer "F.Fab")
		)
		(pad "1" smd circle
			(at -0.40005 0)
			(size 0 0)
			(layers "F.Cu" "F.Mask" "F.Paste")
			(net "OCP_SFF_WAKE_BUFF_N")
		)
		(pad "2" smd circle
			(at 0.40005 0)
			(size 0 0)
			(layers "F.Cu" "F.Mask" "F.Paste")
			(net "OCP_SFF_WAKE_BUFF_R_N")
		)
	)
	(footprint ""
		(layer "F.Cu")
		(at 362.89742 -354.065586)
		(property "Reference" "PC594"
			(at 0 0 0)
			(layer "F.SilkS")
			(hide yes)
			(effects
				(font
					(size 1.27 1.27)
				)
			)
		)
		(property "Value" ""
			(at 0 0 0)
			(layer "F.Fab")
			(effects
				(font
					(size 1.27 1.27)
				)
			)
		)
		(duplicate_pad_numbers_are_jumpers no)
		(fp_line
			(start -0.7874 -0.4064)
			(end 0.7874 -0.4064)
			(stroke
				(width 0.1524)
				(type default)
			)
			(layer "F.SilkS")
		)
		(fp_line
			(start -0.7874 0.4064)
			(end -0.7874 -0.4064)
			(stroke
				(width 0.1524)
				(type default)
			)
			(layer "F.SilkS")
		)
		(fp_line
			(start 0.7874 -0.4064)
			(end 0.7874 0.4064)
			(stroke
				(width 0.1524)
				(type default)
			)
			(layer "F.SilkS")
		)
		(fp_line
			(start 0.7874 0.4064)
			(end -0.7874 0.4064)
			(stroke
				(width 0.1524)
				(type default)
			)
			(layer "F.SilkS")
		)
		(fp_line
			(start -0.67945 -0.305054)
			(end -0.12065 -0.305054)
			(stroke
				(width 0.1)
				(type default)
			)
			(layer "F.Fab")
		)
		(fp_line
			(start -0.67945 0.3048)
			(end -0.67945 -0.305054)
			(stroke
				(width 0.1)
				(type default)
			)
			(layer "F.Fab")
		)
		(fp_line
			(start -0.12065 -0.305054)
			(end -0.12065 -0.2794)
			(stroke
				(width 0.1)
				(type default)
			)
			(layer "F.Fab")
		)
		(fp_line
			(start -0.12065 -0.2794)
			(end 0.12065 -0.2794)
			(stroke
				(width 0.1)
				(type default)
			)
			(layer "F.Fab")
		)
		(fp_line
			(start -0.12065 0.2794)
			(end -0.12065 0.3048)
			(stroke
				(width 0.1)
				(type default)
			)
			(layer "F.Fab")
		)
		(fp_line
			(start -0.12065 0.3048)
			(end -0.67945 0.3048)
			(stroke
				(width 0.1)
				(type default)
			)
			(layer "F.Fab")
		)
		(fp_line
			(start 0.120396 0.2794)
			(end -0.12065 0.2794)
			(stroke
				(width 0.1)
				(type default)
			)
			(layer "F.Fab")
		)
		(fp_line
			(start 0.120396 0.3048)
			(end 0.120396 0.2794)
			(stroke
				(width 0.1)
				(type default)
			)
			(layer "F.Fab")
		)
		(fp_line
			(start 0.12065 -0.3048)
			(end 0.67945 -0.3048)
			(stroke
				(width 0.1)
				(type default)
			)
			(layer "F.Fab")
		)
		(fp_line
			(start 0.12065 -0.2794)
			(end 0.12065 -0.3048)
			(stroke
				(width 0.1)
				(type default)
			)
			(layer "F.Fab")
		)
		(fp_line
			(start 0.67945 -0.3048)
			(end 0.67945 0.3048)
			(stroke
				(width 0.1)
				(type default)
			)
			(layer "F.Fab")
		)
		(fp_line
			(start 0.67945 0.3048)
			(end 0.120396 0.3048)
			(stroke
				(width 0.1)
				(type default)
			)
			(layer "F.Fab")
		)
		(pad "1" smd circle
			(at -0.40005 0)
			(size 0 0)
			(layers "F.Cu" "F.Mask" "F.Paste")
			(net "SH_PVCCFA_EHV_FIVRA_CPU0_R")
		)
		(pad "2" smd circle
			(at 0.40005 0)
			(size 0 0)
			(layers "F.Cu" "F.Mask" "F.Paste")
			(net "VSENSE_PVCCFA_EHV_FIVRA_CPU0_DN")
		)
	)
	(footprint ""
		(layer "F.Cu")
		(at 218.130882 -57.399682 -90)
		(property "Reference" "C2071"
			(at 0 0 270)
			(layer "F.SilkS")
			(hide yes)
			(effects
				(font
					(size 1.27 1.27)
				)
			)
		)
		(property "Value" ""
			(at 0 0 270)
			(layer "F.Fab")
			(effects
				(font
					(size 1.27 1.27)
				)
			)
		)
		(duplicate_pad_numbers_are_jumpers no)
		(fp_line
			(start -0.7874 0.4064)
			(end -0.7874 -0.4064)
			(stroke
				(width 0.1524)
				(type default)
			)
			(layer "F.SilkS")
		)
		(fp_line
			(start 0.7874 0.4064)
			(end -0.7874 0.4064)
			(stroke
				(width 0.1524)
				(type default)
			)
			(layer "F.SilkS")
		)
		(fp_line
			(start -0.7874 -0.4064)
			(end 0.7874 -0.4064)
			(stroke
				(width 0.1524)
				(type default)
			)
			(layer "F.SilkS")
		)
		(fp_line
			(start 0.7874 -0.4064)
			(end 0.7874 0.4064)
			(stroke
				(width 0.1524)
				(type default)
			)
			(layer "F.SilkS")
		)
		(fp_line
			(start -0.67945 0.3048)
			(end -0.67945 -0.305054)
			(stroke
				(width 0.1)
				(type default)
			)
			(layer "F.Fab")
		)
		(fp_line
			(start -0.12065 0.3048)
			(end -0.67945 0.3048)
			(stroke
				(width 0.1)
				(type default)
			)
			(layer "F.Fab")
		)
		(fp_line
			(start 0.120396 0.3048)
			(end 0.120396 0.2794)
			(stroke
				(width 0.1)
				(type default)
			)
			(layer "F.Fab")
		)
		(fp_line
			(start 0.67945 0.3048)
			(end 0.120396 0.3048)
			(stroke
				(width 0.1)
				(type default)
			)
			(layer "F.Fab")
		)
		(fp_line
			(start -0.12065 0.2794)
			(end -0.12065 0.3048)
			(stroke
				(width 0.1)
				(type default)
			)
			(layer "F.Fab")
		)
		(fp_line
			(start 0.120396 0.2794)
			(end -0.12065 0.2794)
			(stroke
				(width 0.1)
				(type default)
			)
			(layer "F.Fab")
		)
		(fp_line
			(start -0.12065 -0.2794)
			(end 0.12065 -0.2794)
			(stroke
				(width 0.1)
				(type default)
			)
			(layer "F.Fab")
		)
		(fp_line
			(start 0.12065 -0.2794)
			(end 0.12065 -0.3048)
			(stroke
				(width 0.1)
				(type default)
			)
			(layer "F.Fab")
		)
		(fp_line
			(start 0.12065 -0.3048)
			(end 0.67945 -0.3048)
			(stroke
				(width 0.1)
				(type default)
			)
			(layer "F.Fab")
		)
		(fp_line
			(start 0.67945 -0.3048)
			(end 0.67945 0.3048)
			(stroke
				(width 0.1)
				(type default)
			)
			(layer "F.Fab")
		)
		(fp_line
			(start -0.67945 -0.305054)
			(end -0.12065 -0.305054)
			(stroke
				(width 0.1)
				(type default)
			)
			(layer "F.Fab")
		)
		(fp_line
			(start -0.12065 -0.305054)
			(end -0.12065 -0.2794)
			(stroke
				(width 0.1)
				(type default)
			)
			(layer "F.Fab")
		)
		(pad "1" smd circle
			(at -0.40005 0 270)
			(size 0 0)
			(layers "F.Cu" "F.Mask" "F.Paste")
			(net "VSENSE_P3V3_INA230_2_INP")
		)
		(pad "2" smd circle
			(at 0.40005 0 270)
			(size 0 0)
			(layers "F.Cu" "F.Mask" "F.Paste")
			(net "VSENSE_P3V3_INA230_2_INN")
		)
	)
	(footprint ""
		(layer "F.Cu")
		(at 93.400118 -333.525368 -90)
		(property "Reference" "PC559_P1_1"
			(at 0 0 270)
			(layer "F.SilkS")
			(hide yes)
			(effects
				(font
					(size 1.27 1.27)
				)
			)
		)
		(property "Value" ""
			(at 0 0 270)
			(layer "F.Fab")
			(effects
				(font
					(size 1.27 1.27)
				)
			)
		)
		(duplicate_pad_numbers_are_jumpers no)
		(fp_line
			(start -0.7874 0.4064)
			(end -0.7874 -0.4064)
			(stroke
				(width 0.1524)
				(type default)
			)
			(layer "F.SilkS")
		)
		(fp_line
			(start 0.7874 0.4064)
			(end -0.7874 0.4064)
			(stroke
				(width 0.1524)
				(type default)
			)
			(layer "F.SilkS")
		)
		(fp_line
			(start -0.7874 -0.4064)
			(end 0.7874 -0.4064)
			(stroke
				(width 0.1524)
				(type default)
			)
			(layer "F.SilkS")
		)
		(fp_line
			(start 0.7874 -0.4064)
			(end 0.7874 0.4064)
			(stroke
				(width 0.1524)
				(type default)
			)
			(layer "F.SilkS")
		)
		(fp_line
			(start -0.67945 0.3048)
			(end -0.67945 -0.305054)
			(stroke
				(width 0.1)
				(type default)
			)
			(layer "F.Fab")
		)
		(fp_line
			(start -0.12065 0.3048)
			(end -0.67945 0.3048)
			(stroke
				(width 0.1)
				(type default)
			)
			(layer "F.Fab")
		)
		(fp_line
			(start 0.120396 0.3048)
			(end 0.120396 0.2794)
			(stroke
				(width 0.1)
				(type default)
			)
			(layer "F.Fab")
		)
		(fp_line
			(start 0.67945 0.3048)
			(end 0.120396 0.3048)
			(stroke
				(width 0.1)
				(type default)
			)
			(layer "F.Fab")
		)
		(fp_line
			(start -0.12065 0.2794)
			(end -0.12065 0.3048)
			(stroke
				(width 0.1)
				(type default)
			)
			(layer "F.Fab")
		)
		(fp_line
			(start 0.120396 0.2794)
			(end -0.12065 0.2794)
			(stroke
				(width 0.1)
				(type default)
			)
			(layer "F.Fab")
		)
		(fp_line
			(start -0.12065 -0.2794)
			(end 0.12065 -0.2794)
			(stroke
				(width 0.1)
				(type default)
			)
			(layer "F.Fab")
		)
		(fp_line
			(start 0.12065 -0.2794)
			(end 0.12065 -0.3048)
			(stroke
				(width 0.1)
				(type default)
			)
			(layer "F.Fab")
		)
		(fp_line
			(start 0.12065 -0.3048)
			(end 0.67945 -0.3048)
			(stroke
				(width 0.1)
				(type default)
			)
			(layer "F.Fab")
		)
		(fp_line
			(start 0.67945 -0.3048)
			(end 0.67945 0.3048)
			(stroke
				(width 0.1)
				(type default)
			)
			(layer "F.Fab")
		)
		(fp_line
			(start -0.67945 -0.305054)
			(end -0.12065 -0.305054)
			(stroke
				(width 0.1)
				(type default)
			)
			(layer "F.Fab")
		)
		(fp_line
			(start -0.12065 -0.305054)
			(end -0.12065 -0.2794)
			(stroke
				(width 0.1)
				(type default)
			)
			(layer "F.Fab")
		)
		(pad "1" smd circle
			(at -0.40005 0 270)
			(size 0 0)
			(layers "F.Cu" "F.Mask" "F.Paste")
			(net "PVCCIN_CPU1_PVCC")
		)
		(pad "2" smd circle
			(at 0.40005 0 270)
			(size 0 0)
			(layers "F.Cu" "F.Mask" "F.Paste")
			(net "GND")
		)
	)
	(footprint ""
		(layer "F.Cu")
		(at 254.58674 -92.291408 180)
		(property "Reference" "R3643"
			(at 0 0 180)
			(layer "F.SilkS")
			(hide yes)
			(effects
				(font
					(size 1.27 1.27)
				)
			)
		)
		(property "Value" ""
			(at 0 0 180)
			(layer "F.Fab")
			(effects
				(font
					(size 1.27 1.27)
				)
			)
		)
		(duplicate_pad_numbers_are_jumpers no)
		(fp_line
			(start 0.7874 0.4064)
			(end -0.7874 0.4064)
			(stroke
				(width 0.1524)
				(type default)
			)
			(layer "F.SilkS")
		)
		(fp_line
			(start 0.7874 -0.4064)
			(end 0.7874 0.4064)
			(stroke
				(width 0.1524)
				(type default)
			)
			(layer "F.SilkS")
		)
		(fp_line
			(start -0.7874 0.4064)
			(end -0.7874 -0.4064)
			(stroke
				(width 0.1524)
				(type default)
			)
			(layer "F.SilkS")
		)
		(fp_line
			(start -0.7874 -0.4064)
			(end 0.7874 -0.4064)
			(stroke
				(width 0.1524)
				(type default)
			)
			(layer "F.SilkS")
		)
		(fp_line
			(start 0.67945 0.3048)
			(end 0.120396 0.3048)
			(stroke
				(width 0.1)
				(type default)
			)
			(layer "F.Fab")
		)
		(fp_line
			(start 0.67945 -0.3048)
			(end 0.67945 0.3048)
			(stroke
				(width 0.1)
				(type default)
			)
			(layer "F.Fab")
		)
		(fp_line
			(start 0.12065 -0.2794)
			(end 0.12065 -0.3048)
			(stroke
				(width 0.1)
				(type default)
			)
			(layer "F.Fab")
		)
		(fp_line
			(start 0.12065 -0.3048)
			(end 0.67945 -0.3048)
			(stroke
				(width 0.1)
				(type default)
			)
			(layer "F.Fab")
		)
		(fp_line
			(start 0.120396 0.3048)
			(end 0.120396 0.2794)
			(stroke
				(width 0.1)
				(type default)
			)
			(layer "F.Fab")
		)
		(fp_line
			(start 0.120396 0.2794)
			(end -0.12065 0.2794)
			(stroke
				(width 0.1)
				(type default)
			)
			(layer "F.Fab")
		)
		(fp_line
			(start -0.12065 0.3048)
			(end -0.67945 0.3048)
			(stroke
				(width 0.1)
				(type default)
			)
			(layer "F.Fab")
		)
		(fp_line
			(start -0.12065 0.2794)
			(end -0.12065 0.3048)
			(stroke
				(width 0.1)
				(type default)
			)
			(layer "F.Fab")
		)
		(fp_line
			(start -0.12065 -0.2794)
			(end 0.12065 -0.2794)
			(stroke
				(width 0.1)
				(type default)
			)
			(layer "F.Fab")
		)
		(fp_line
			(start -0.12065 -0.305054)
			(end -0.12065 -0.2794)
			(stroke
				(width 0.1)
				(type default)
			)
			(layer "F.Fab")
		)
		(fp_line
			(start -0.67945 0.3048)
			(end -0.67945 -0.305054)
			(stroke
				(width 0.1)
				(type default)
			)
			(layer "F.Fab")
		)
		(fp_line
			(start -0.67945 -0.305054)
			(end -0.12065 -0.305054)
			(stroke
				(width 0.1)
				(type default)
			)
			(layer "F.Fab")
		)
		(pad "1" smd circle
			(at -0.40005 0 180)
			(size 0 0)
			(layers "F.Cu" "F.Mask" "F.Paste")
			(net "P3V3_AUX")
		)
		(pad "2" smd circle
			(at 0.40005 0 180)
			(size 0 0)
			(layers "F.Cu" "F.Mask" "F.Paste")
			(net "CK440Q_OE_6")
		)
	)
)
